# BASEBOARD_FAB2 (Tioga Pass) — schematic netlist excerpt (pin names and nets, part order shuffled) for the footprints in the layout excerpt that follows; sources: Cadence DE-HDL packaged netlist, KiCad conversion of Wiwynn_Tioga_Pass_MB.brd

RM1G1  STFT363B238R224H453-GP  pkg DISCRET-GC1  page 195 : \1\ = GND
C4E23  CAP  0.22UF 16V 10% X7R  pkg 0402  page 214 : A = P5V_STBY ; B = GND
C25W8  CAP_A  0.1UF 16V 10% X7R  pkg 0402V  page 147 : A = P3V3_STBY_BMC_ADCVREFN ; B = GND

(kicad_pcb
	(version 20260206)
	(generator "pcbnew")
	(generator_version "10.0")
	(general
		(thickness 1.6)
		(legacy_teardrops no)
	)
	(paper "A4")
	(title_block
		(title "Wiwynn_Tioga_Pass_MB.brd")
		(comment 1 "Tioga Pass / footprints 1112-1114 of 4770")
	)
	(layers
		(0 "F.Cu" signal "TOP")
		(4 "In1.Cu" signal "L2GND")
		(6 "In2.Cu" signal "L3")
		(8 "In3.Cu" signal "L4GND")
		(10 "In4.Cu" signal "L5")
		(12 "In5.Cu" signal "L6GND")
		(14 "In6.Cu" signal "L7VCC")
		(16 "In7.Cu" signal "L8VCC")
		(18 "In8.Cu" signal "L9GND")
		(20 "In9.Cu" signal "L10")
		(22 "In10.Cu" signal "L11GND")
		(24 "In11.Cu" signal "L12")
		(26 "In12.Cu" signal "L13GND")
		(2 "B.Cu" signal "BOTTOM")
		(9 "F.Adhes" user "F.Adhesive")
		(11 "B.Adhes" user "B.Adhesive")
		(13 "F.Paste" user "Package Geometry/Pastemask Top")
		(15 "B.Paste" user "Package Geometry/Pastemask Bottom")
		(5 "F.SilkS" user "Ref Des/Silkscreen Top")
		(7 "B.SilkS" user "Ref Des/Silkscreen Bottom")
		(1 "F.Mask" user "Board Geometry/Soldermask Top")
		(3 "B.Mask" user "Board Geometry/Soldermask Bottom")
		(17 "Dwgs.User" user "User.Drawings")
		(19 "Cmts.User" user "User.Comments")
		(21 "Eco1.User" user "User.Eco1")
		(23 "Eco2.User" user "User.Eco2")
		(25 "Edge.Cuts" user "Board Geometry/Outline")
		(27 "Margin" user)
		(31 "F.CrtYd" user "Package Geometry/Place Bound Top")
		(29 "B.CrtYd" user "Package Geometry/Place Bound Bottom")
		(35 "F.Fab" user "Ref Des/Assembly Top")
		(33 "B.Fab" user "Ref Des/Assembly Bottom")
	)
	(footprint ""
		(layer "F.Cu")
		(at 178.181 -58.166 -90)
		(property "Reference" "C4E23"
			(at 0 0 270)
			(layer "F.SilkS")
			(hide yes)
			(effects
				(font
					(size 1.27 1.27)
				)
			)
		)
		(property "Value" ""
			(at 0 0 270)
			(layer "F.Fab")
			(effects
				(font
					(size 1.27 1.27)
				)
			)
		)
		(duplicate_pad_numbers_are_jumpers no)
		(fp_poly
			(pts
				(xy 0.3048 -0.1016) (xy 0.3048 0.9906) (xy -0.3048 0.9906) (xy -0.3048 -0.1016)
			)
			(stroke
				(width 0)
				(type default)
			)
			(fill no)
			(layer "F.CrtYd")
		)
		(fp_line
			(start -0.3048 0.9906)
			(end 0.3048 0.9906)
			(stroke
				(width 0.1)
				(type default)
			)
			(layer "F.Fab")
		)
		(fp_line
			(start 0.3048 0.9906)
			(end 0.3048 -0.1016)
			(stroke
				(width 0.1)
				(type default)
			)
			(layer "F.Fab")
		)
		(fp_line
			(start -0.3048 -0.1016)
			(end -0.3048 0.9906)
			(stroke
				(width 0.1)
				(type default)
			)
			(layer "F.Fab")
		)
		(fp_line
			(start 0.3048 -0.1016)
			(end -0.3048 -0.1016)
			(stroke
				(width 0.1)
				(type default)
			)
			(layer "F.Fab")
		)
		(pad "1" smd rect
			(at 0 0 270)
			(size 0.508 0.508)
			(layers "F.Cu" "F.Mask" "F.Paste")
			(net "P5V_STBY")
		)
		(pad "2" smd rect
			(at 0 0.889 270)
			(size 0.508 0.508)
			(layers "F.Cu" "F.Mask" "F.Paste")
			(net "GND")
		)
		(zone
			(layer "F.Cu")
			(hatch none 0.5)
			(connect_pads
				(clearance 0)
			)
			(min_thickness 0.25)
			(keepout
				(tracks not_allowed)
				(vias allowed)
				(pads allowed)
				(copperpour not_allowed)
				(footprints allowed)
			)
			(placement
				(enabled no)
				(sheetname "")
			)
			(fill
				(thermal_gap 0.5)
				(thermal_bridge_width 0.5)
				(island_removal_mode 0)
			)
			(polygon
				(pts
					(xy 177.546 -58.42) (xy 177.546 -57.912) (xy 177.927 -57.912) (xy 177.927 -58.42)
				)
			)
		)
		(zone
			(layer "F.Cu")
			(hatch none 0.5)
			(connect_pads
				(clearance 0)
			)
			(min_thickness 0.25)
			(keepout
				(tracks allowed)
				(vias not_allowed)
				(pads allowed)
				(copperpour not_allowed)
				(footprints allowed)
			)
			(placement
				(enabled no)
				(sheetname "")
			)
			(fill
				(thermal_gap 0.5)
				(thermal_bridge_width 0.5)
				(island_removal_mode 0)
			)
			(polygon
				(pts
					(xy 177.927 -58.42) (xy 177.927 -57.912) (xy 177.546 -57.912) (xy 177.546 -58.42)
				)
			)
		)
	)
	(footprint ""
		(layer "F.Cu")
		(at 0 0 90)
		(property "Reference" "RM1G1"
			(at 0 0 90)
			(layer "F.SilkS")
			(hide yes)
			(effects
				(font
					(size 1.27 1.27)
				)
			)
		)
		(property "Value" "*"
			(at 7.0612 1.3462 90)
			(unlocked yes)
			(layer "F.Fab")
			(hide yes)
			(effects
				(font
					(size 1.27 1.016)
					(thickness 0.1524)
				)
			)
		)
		(property "Device Type" "STFT363B238R224H453-GP_DISCRETA"
			(at 7.0612 -0.1778 90)
			(unlocked yes)
			(layer "F.Fab")
			(hide yes)
			(effects
				(font
					(size 1.27 1.016)
					(thickness 0.1524)
				)
			)
		)
		(duplicate_pad_numbers_are_jumpers no)
		(fp_circle
			(center 0 0)
			(end 0 5.3594)
			(stroke
				(width 0.3048)
				(type default)
			)
			(fill no)
			(layer "F.SilkS")
		)
		(fp_poly
			(pts
				(arc
					(start 0 3.5306)
					(mid 0 -3.5306)
					(end 0 3.5306)
				)
			)
			(stroke
				(width 0)
				(type default)
			)
			(fill no)
			(layer "B.CrtYd")
		)
		(fp_poly
			(pts
				(arc
					(start 0 5.0038)
					(mid 0 -5.0038)
					(end 0 5.0038)
				)
			)
			(stroke
				(width 0)
				(type default)
			)
			(fill no)
			(layer "F.CrtYd")
		)
		(fp_poly
			(pts
				(arc
					(start 5.5118 0.00635)
					(mid -5.511804 0)
					(end 5.5118 -0.00635)
				)
				(arc
					(start 5.0038 -0.00635)
					(mid -5.003804 0)
					(end 5.0038 0.00635)
				)
			)
			(stroke
				(width 0)
				(type default)
			)
			(fill no)
			(layer "F.CrtYd")
		)
		(fp_poly
			(pts
				(arc
					(start 0 3.5306)
					(mid 0 -3.5306)
					(end 0 3.5306)
				)
			)
			(stroke
				(width 0)
				(type default)
			)
			(fill no)
			(layer "B.Fab")
		)
		(fp_poly
			(pts
				(arc
					(start 0 5.5118)
					(mid 0 -5.5118)
					(end 0 5.5118)
				)
			)
			(stroke
				(width 0)
				(type default)
			)
			(fill no)
			(layer "F.Fab")
		)
		(pad "1" thru_hole circle
			(at 0 0 90)
			(size 9.2202 9.2202)
			(drill 5.6896)
			(layers "*.Cu" "*.Mask")
			(remove_unused_layers no)
			(net "GND")
			(clearance -1.2573)
			(thermal_gap 0.3302)
			(padstack
				(mode front_inner_back)
				(layer "Inner"
					(shape circle)
					(size 6.0452 6.0452)
					(clearance 0.3302)
				)
				(layer "B.Cu"
					(shape circle)
					(size 6.0452 6.0452)
					(clearance 0.3302)
				)
			)
		)
	)
	(footprint ""
		(layer "F.Cu")
		(at 411.975046 -22.196552)
		(property "Reference" "C25W8"
			(at -0.8382 -0.67818 0)
			(unlocked yes)
			(layer "F.SilkS")
			(effects
				(font
					(size 0.4064 0.254)
					(thickness 0.1524)
				)
				(justify left)
			)
		)
		(property "Value" ""
			(at 0 0 0)
			(layer "F.Fab")
			(effects
				(font
					(size 1.27 1.27)
				)
			)
		)
		(duplicate_pad_numbers_are_jumpers no)
		(fp_poly
			(pts
				(xy 0.3048 -0.1016) (xy 0.3048 0.9906) (xy -0.3048 0.9906) (xy -0.3048 -0.1016)
			)
			(stroke
				(width 0)
				(type default)
			)
			(fill no)
			(layer "F.CrtYd")
		)
		(fp_line
			(start -0.3048 -0.1016)
			(end -0.3048 0.9906)
			(stroke
				(width 0.1)
				(type default)
			)
			(layer "F.Fab")
		)
		(fp_line
			(start -0.3048 0.9906)
			(end 0.3048 0.9906)
			(stroke
				(width 0.1)
				(type default)
			)
			(layer "F.Fab")
		)
		(fp_line
			(start 0.3048 -0.1016)
			(end -0.3048 -0.1016)
			(stroke
				(width 0.1)
				(type default)
			)
			(layer "F.Fab")
		)
		(fp_line
			(start 0.3048 0.9906)
			(end 0.3048 -0.1016)
			(stroke
				(width 0.1)
				(type default)
			)
			(layer "F.Fab")
		)
		(pad "1" smd rect
			(at 0 0)
			(size 0.508 0.508)
			(layers "F.Cu" "F.Mask" "F.Paste")
			(net "P3V3_STBY_BMC_ADCVREFN")
		)
		(pad "2" smd rect
			(at 0 0.889)
			(size 0.508 0.508)
			(layers "F.Cu" "F.Mask" "F.Paste")
			(net "GND")
		)
		(zone
			(layer "F.Cu")
			(hatch none 0.5)
			(connect_pads
				(clearance 0)
			)
			(min_thickness 0.25)
			(keepout
				(tracks allowed)
				(vias not_allowed)
				(pads allowed)
				(copperpour not_allowed)
				(footprints allowed)
			)
			(placement
				(enabled no)
				(sheetname "")
			)
			(fill
				(thermal_gap 0.5)
				(thermal_bridge_width 0.5)
				(island_removal_mode 0)
			)
			(polygon
				(pts
					(xy 411.721046 -21.942552) (xy 412.229046 -21.942552) (xy 412.229046 -21.561552) (xy 411.721046 -21.561552)
				)
			)
		)
		(zone
			(layer "F.Cu")
			(hatch none 0.5)
			(connect_pads
				(clearance 0)
			)
			(min_thickness 0.25)
			(keepout
				(tracks not_allowed)
				(vias allowed)
				(pads allowed)
				(copperpour not_allowed)
				(footprints allowed)
			)
			(placement
				(enabled no)
				(sheetname "")
			)
			(fill
				(thermal_gap 0.5)
				(thermal_bridge_width 0.5)
				(island_removal_mode 0)
			)
			(polygon
				(pts
					(xy 411.721046 -21.561552) (xy 412.229046 -21.561552) (xy 412.229046 -21.942552) (xy 411.721046 -21.942552)
				)
			)
		)
	)
)
